G04 ================== begin FILE IDENTIFICATION RECORD ==================*
G04 Layout Name:  14629-1a.brd*
G04 Film Name:    TSMD*
G04 File Format:  Gerber RS274X*
G04 File Origin:  Cadence Allegro 16.5-S037*
G04 Origin Date:  Tue Nov 25 11:50:45 2014*
G04 *
G04 Layer:  VIA CLASS/PASTEMASK_TOP*
G04 Layer:  PIN/PASTEMASK_TOP*
G04 Layer:  PACKAGE GEOMETRY/PASTEMASK_TOP*
G04 Layer:  DRAWING FORMAT/LAYER_PCB_STORY*
G04 Layer:  DRAWING FORMAT/LAYER_PAST_T*
G04 Layer:  BOARD GEOMETRY/PANEL_OUTLINE*
G04 *
G04 Offset:    (0.00 0.00)*
G04 Mirror:    No*
G04 Mode:      Positive*
G04 Rotation:  0*
G04 FullContactRelief:  No*
G04 UndefLineWidth:     6.00*
G04 ================== end FILE IDENTIFICATION RECORD ====================*
%FSLAX35Y35*MOIN*%
%IR0*IPPOS*OFA0.00000B0.00000*MIA0B0*SFA1.00000B1.00000*%
%AMMACRO12*
4,1,40,.017,-.013,
.017,.013,
.016939,.013695,
.016759,.014368,
.016464,.015,
.016064,.015571,
.015571,.016064,
.015,.016464,
.014368,.016759,
.013695,.016939,
.013,.017,
-.013,.017,
-.013695,.016939,
-.014368,.016759,
-.015,.016464,
-.015571,.016064,
-.016064,.015571,
-.016464,.015,
-.016759,.014368,
-.016939,.013695,
-.017,.013,
-.017,-.013,
-.016939,-.013695,
-.016759,-.014368,
-.016464,-.015,
-.016064,-.015571,
-.015571,-.016064,
-.015,-.016464,
-.014368,-.016759,
-.013695,-.016939,
-.013,-.017,
.013,-.017,
.013695,-.016939,
.014368,-.016759,
.015,-.016464,
.015571,-.016064,
.016064,-.015571,
.016464,-.015,
.016759,-.014368,
.016939,-.013695,
.017,-.013,
0.0*
%
%ADD12MACRO12*%
%ADD28R,.11X.055*%
%ADD31R,.074X.122*%
%ADD10C,.04*%
%ADD27C,.032*%
%AMMACRO26*
4,1,40,.007,.011,
-.007,.011,
-.007695,.010939,
-.008368,.010759,
-.009,.010464,
-.009571,.010064,
-.010064,.009571,
-.010464,.009,
-.010759,.008368,
-.010939,.007695,
-.011,.007,
-.011,-.007,
-.010939,-.007695,
-.010759,-.008368,
-.010464,-.009,
-.010064,-.009571,
-.009571,-.010064,
-.009,-.010464,
-.008368,-.010759,
-.007695,-.010939,
-.007,-.011,
.007,-.011,
.007695,-.010939,
.008368,-.010759,
.009,-.010464,
.009571,-.010064,
.010064,-.009571,
.010464,-.009,
.010759,-.008368,
.010939,-.007695,
.011,-.007,
.011,.007,
.010939,.007695,
.010759,.008368,
.010464,.009,
.010064,.009571,
.009571,.010064,
.009,.010464,
.008368,.010759,
.007695,.010939,
.007,.011,
0.0*
%
%ADD26MACRO26*%
%AMMACRO23*
4,1,40,.011,-.007,
.011,.007,
.010939,.007695,
.010759,.008368,
.010464,.009,
.010064,.009571,
.009571,.010064,
.009,.010464,
.008368,.010759,
.007695,.010939,
.007,.011,
-.007,.011,
-.007695,.010939,
-.008368,.010759,
-.009,.010464,
-.009571,.010064,
-.010064,.009571,
-.010464,.009,
-.010759,.008368,
-.010939,.007695,
-.011,.007,
-.011,-.007,
-.010939,-.007695,
-.010759,-.008368,
-.010464,-.009,
-.010064,-.009571,
-.009571,-.010064,
-.009,-.010464,
-.008368,-.010759,
-.007695,-.010939,
-.007,-.011,
.007,-.011,
.007695,-.010939,
.008368,-.010759,
.009,-.010464,
.009571,-.010064,
.010064,-.009571,
.010464,-.009,
.010759,-.008368,
.010939,-.007695,
.011,-.007,
0.0*
%
%ADD23MACRO23*%
%AMMACRO20*
4,1,40,-.017,.013,
-.017,-.013,
-.016939,-.013695,
-.016759,-.014368,
-.016464,-.015,
-.016064,-.015571,
-.015571,-.016064,
-.015,-.016464,
-.014368,-.016759,
-.013695,-.016939,
-.013,-.017,
.013,-.017,
.013695,-.016939,
.014368,-.016759,
.015,-.016464,
.015571,-.016064,
.016064,-.015571,
.016464,-.015,
.016759,-.014368,
.016939,-.013695,
.017,-.013,
.017,.013,
.016939,.013695,
.016759,.014368,
.016464,.015,
.016064,.015571,
.015571,.016064,
.015,.016464,
.014368,.016759,
.013695,.016939,
.013,.017,
-.013,.017,
-.013695,.016939,
-.014368,.016759,
-.015,.016464,
-.015571,.016064,
-.016064,.015571,
-.016464,.015,
-.016759,.014368,
-.016939,.013695,
-.017,.013,
0.0*
%
%ADD20MACRO20*%
%AMMACRO25*
4,1,40,.007,.011,
-.007,.011,
-.007695,.010939,
-.008368,.010759,
-.009,.010464,
-.009571,.010064,
-.010064,.009571,
-.010464,.009,
-.010759,.008368,
-.010939,.007695,
-.011,.007,
-.011,-.007,
-.010939,-.007695,
-.010759,-.008368,
-.010464,-.009,
-.010064,-.009571,
-.009571,-.010064,
-.009,-.010464,
-.008368,-.010759,
-.007695,-.010939,
-.007,-.011,
.007,-.011,
.007695,-.010939,
.008368,-.010759,
.009,-.010464,
.009571,-.010064,
.010064,-.009571,
.010464,-.009,
.010759,-.008368,
.010939,-.007695,
.011,-.007,
.011,.007,
.010939,.007695,
.010759,.008368,
.010464,.009,
.010064,.009571,
.009571,.010064,
.009,.010464,
.008368,.010759,
.007695,.010939,
.007,.011,
0.0*
%
%ADD25MACRO25*%
%AMMACRO16*
4,1,40,.011,-.007,
.011,.007,
.010939,.007695,
.010759,.008368,
.010464,.009,
.010064,.009571,
.009571,.010064,
.009,.010464,
.008368,.010759,
.007695,.010939,
.007,.011,
-.007,.011,
-.007695,.010939,
-.008368,.010759,
-.009,.010464,
-.009571,.010064,
-.010064,.009571,
-.010464,.009,
-.010759,.008368,
-.010939,.007695,
-.011,.007,
-.011,-.007,
-.010939,-.007695,
-.010759,-.008368,
-.010464,-.009,
-.010064,-.009571,
-.009571,-.010064,
-.009,-.010464,
-.008368,-.010759,
-.007695,-.010939,
-.007,-.011,
.007,-.011,
.007695,-.010939,
.008368,-.010759,
.009,-.010464,
.009571,-.010064,
.010064,-.009571,
.010464,-.009,
.010759,-.008368,
.010939,-.007695,
.011,-.007,
0.0*
%
%ADD16MACRO16*%
%AMMACRO13*
4,1,40,-.017,.013,
-.017,-.013,
-.016939,-.013695,
-.016759,-.014368,
-.016464,-.015,
-.016064,-.015571,
-.015571,-.016064,
-.015,-.016464,
-.014368,-.016759,
-.013695,-.016939,
-.013,-.017,
.013,-.017,
.013695,-.016939,
.014368,-.016759,
.015,-.016464,
.015571,-.016064,
.016064,-.015571,
.016464,-.015,
.016759,-.014368,
.016939,-.013695,
.017,-.013,
.017,.013,
.016939,.013695,
.016759,.014368,
.016464,.015,
.016064,.015571,
.015571,.016064,
.015,.016464,
.014368,.016759,
.013695,.016939,
.013,.017,
-.013,.017,
-.013695,.016939,
-.014368,.016759,
-.015,.016464,
-.015571,.016064,
-.016064,.015571,
-.016464,.015,
-.016759,.014368,
-.016939,.013695,
-.017,.013,
0.0*
%
%ADD13MACRO13*%
%ADD18R,.016X.06*%
%ADD11R,.055X.045*%
%AMMACRO30*
4,1,40,.007,.0225,
.008389,.022378,
.009736,.022018,
.011,.021428,
.012142,.020628,
.013128,.019642,
.013928,.0185,
.014518,.017236,
.014878,.015889,
.015,.0145,
.015,-.0145,
.014878,-.015889,
.014518,-.017236,
.013928,-.0185,
.013128,-.019642,
.012142,-.020628,
.011,-.021428,
.009736,-.022018,
.008389,-.022378,
.007,-.0225,
-.007,-.0225,
-.008389,-.022378,
-.009736,-.022018,
-.011,-.021428,
-.012142,-.020628,
-.013128,-.019642,
-.013928,-.0185,
-.014518,-.017236,
-.014878,-.015889,
-.015,-.0145,
-.015,.0145,
-.014878,.015889,
-.014518,.017236,
-.013928,.0185,
-.013128,.019642,
-.012142,.020628,
-.011,.021428,
-.009736,.022018,
-.008389,.022378,
-.007,.0225,
.007,.0225,
0.0*
%
%ADD30MACRO30*%
%ADD29R,.095X.09*%
%AMMACRO24*
4,1,40,-.008,-.012,
.008,-.012,
.008695,-.011939,
.009368,-.011759,
.01,-.011464,
.010571,-.011064,
.011064,-.010571,
.011464,-.01,
.011759,-.009368,
.011939,-.008695,
.012,-.008,
.012,.008,
.011939,.008695,
.011759,.009368,
.011464,.01,
.011064,.010571,
.010571,.011064,
.01,.011464,
.009368,.011759,
.008695,.011939,
.008,.012,
-.008,.012,
-.008695,.011939,
-.009368,.011759,
-.01,.011464,
-.010571,.011064,
-.011064,.010571,
-.011464,.01,
-.011759,.009368,
-.011939,.008695,
-.012,.008,
-.012,-.008,
-.011939,-.008695,
-.011759,-.009368,
-.011464,-.01,
-.011064,-.010571,
-.010571,-.011064,
-.01,-.011464,
-.009368,-.011759,
-.008695,-.011939,
-.008,-.012,
0.0*
%
%ADD24MACRO24*%
%AMMACRO22*
4,1,40,-.007,-.011,
.007,-.011,
.007695,-.010939,
.008368,-.010759,
.009,-.010464,
.009571,-.010064,
.010064,-.009571,
.010464,-.009,
.010759,-.008368,
.010939,-.007695,
.011,-.007,
.011,.007,
.010939,.007695,
.010759,.008368,
.010464,.009,
.010064,.009571,
.009571,.010064,
.009,.010464,
.008368,.010759,
.007695,.010939,
.007,.011,
-.007,.011,
-.007695,.010939,
-.008368,.010759,
-.009,.010464,
-.009571,.010064,
-.010064,.009571,
-.010464,.009,
-.010759,.008368,
-.010939,.007695,
-.011,.007,
-.011,-.007,
-.010939,-.007695,
-.010759,-.008368,
-.010464,-.009,
-.010064,-.009571,
-.009571,-.010064,
-.009,-.010464,
-.008368,-.010759,
-.007695,-.010939,
-.007,-.011,
0.0*
%
%ADD22MACRO22*%
%AMMACRO21*
4,1,40,-.011,.007,
-.011,-.007,
-.010939,-.007695,
-.010759,-.008368,
-.010464,-.009,
-.010064,-.009571,
-.009571,-.010064,
-.009,-.010464,
-.008368,-.010759,
-.007695,-.010939,
-.007,-.011,
.007,-.011,
.007695,-.010939,
.008368,-.010759,
.009,-.010464,
.009571,-.010064,
.010064,-.009571,
.010464,-.009,
.010759,-.008368,
.010939,-.007695,
.011,-.007,
.011,.007,
.010939,.007695,
.010759,.008368,
.010464,.009,
.010064,.009571,
.009571,.010064,
.009,.010464,
.008368,.010759,
.007695,.010939,
.007,.011,
-.007,.011,
-.007695,.010939,
-.008368,.010759,
-.009,.010464,
-.009571,.010064,
-.010064,.009571,
-.010464,.009,
-.010759,.008368,
-.010939,.007695,
-.011,.007,
0.0*
%
%ADD21MACRO21*%
%AMMACRO19*
4,1,40,.017,-.013,
.017,.013,
.016939,.013695,
.016759,.014368,
.016464,.015,
.016064,.015571,
.015571,.016064,
.015,.016464,
.014368,.016759,
.013695,.016939,
.013,.017,
-.013,.017,
-.013695,.016939,
-.014368,.016759,
-.015,.016464,
-.015571,.016064,
-.016064,.015571,
-.016464,.015,
-.016759,.014368,
-.016939,.013695,
-.017,.013,
-.017,-.013,
-.016939,-.013695,
-.016759,-.014368,
-.016464,-.015,
-.016064,-.015571,
-.015571,-.016064,
-.015,-.016464,
-.014368,-.016759,
-.013695,-.016939,
-.013,-.017,
.013,-.017,
.013695,-.016939,
.014368,-.016759,
.015,-.016464,
.015571,-.016064,
.016064,-.015571,
.016464,-.015,
.016759,-.014368,
.016939,-.013695,
.017,-.013,
0.0*
%
%ADD19MACRO19*%
%AMMACRO15*
4,1,40,-.007,-.011,
.007,-.011,
.007695,-.010939,
.008368,-.010759,
.009,-.010464,
.009571,-.010064,
.010064,-.009571,
.010464,-.009,
.010759,-.008368,
.010939,-.007695,
.011,-.007,
.011,.007,
.010939,.007695,
.010759,.008368,
.010464,.009,
.010064,.009571,
.009571,.010064,
.009,.010464,
.008368,.010759,
.007695,.010939,
.007,.011,
-.007,.011,
-.007695,.010939,
-.008368,.010759,
-.009,.010464,
-.009571,.010064,
-.010064,.009571,
-.010464,.009,
-.010759,.008368,
-.010939,.007695,
-.011,.007,
-.011,-.007,
-.010939,-.007695,
-.010759,-.008368,
-.010464,-.009,
-.010064,-.009571,
-.009571,-.010064,
-.009,-.010464,
-.008368,-.010759,
-.007695,-.010939,
-.007,-.011,
0.0*
%
%ADD15MACRO15*%
%AMMACRO14*
4,1,40,-.008,-.012,
.008,-.012,
.008695,-.011939,
.009368,-.011759,
.01,-.011464,
.010571,-.011064,
.011064,-.010571,
.011464,-.01,
.011759,-.009368,
.011939,-.008695,
.012,-.008,
.012,.008,
.011939,.008695,
.011759,.009368,
.011464,.01,
.011064,.010571,
.010571,.011064,
.01,.011464,
.009368,.011759,
.008695,.011939,
.008,.012,
-.008,.012,
-.008695,.011939,
-.009368,.011759,
-.01,.011464,
-.010571,.011064,
-.011064,.010571,
-.011464,.01,
-.011759,.009368,
-.011939,.008695,
-.012,.008,
-.012,-.008,
-.011939,-.008695,
-.011759,-.009368,
-.011464,-.01,
-.011064,-.010571,
-.010571,-.011064,
-.01,-.011464,
-.009368,-.011759,
-.008695,-.011939,
-.008,-.012,
0.0*
%
%ADD14MACRO14*%
%AMMACRO17*
4,1,40,-.011,.007,
-.011,-.007,
-.010939,-.007695,
-.010759,-.008368,
-.010464,-.009,
-.010064,-.009571,
-.009571,-.010064,
-.009,-.010464,
-.008368,-.010759,
-.007695,-.010939,
-.007,-.011,
.007,-.011,
.007695,-.010939,
.008368,-.010759,
.009,-.010464,
.009571,-.010064,
.010064,-.009571,
.010464,-.009,
.010759,-.008368,
.010939,-.007695,
.011,-.007,
.011,.007,
.010939,.007695,
.010759,.008368,
.010464,.009,
.010064,.009571,
.009571,.010064,
.009,.010464,
.008368,.010759,
.007695,.010939,
.007,.011,
-.007,.011,
-.007695,.010939,
-.008368,.010759,
-.009,.010464,
-.009571,.010064,
-.010064,.009571,
-.010464,.009,
-.010759,.008368,
-.010939,.007695,
-.011,.007,
0.0*
%
%ADD17MACRO17*%
%ADD32C,.02*%
%ADD33C,.006*%
G75*
%LPD*%
G75*
G54D10*
X-23622Y62794D03*
Y916269D03*
X1297695Y58466D03*
G54D11*
X197Y189819D03*
Y197419D03*
X9297Y189819D03*
Y197419D03*
X472898Y182636D03*
Y190236D03*
X550498Y322336D03*
Y329936D03*
G54D20*
X38109Y363133D03*
X542500Y258171D03*
X618000Y71700D03*
X617798Y403136D03*
X612798Y403036D03*
G54D21*
X51094Y387325D03*
X60052Y387292D03*
X55352Y387374D03*
X43159Y373885D03*
X43072Y365847D03*
X538000Y293300D03*
X548000Y429300D03*
G54D30*
X529036Y308352D03*
X525161Y315852D03*
X532911D03*
X529011Y293257D03*
X532886Y300757D03*
X525136D03*
G54D12*
X38128Y374332D03*
X45807Y388068D03*
X542500Y269171D03*
X634488Y72003D03*
G54D22*
X38598Y333436D03*
Y337936D03*
X33508Y368932D03*
Y374132D03*
X69498Y369470D03*
X69547Y373979D03*
X69550Y378236D03*
X537733Y268971D03*
Y263971D03*
X533636Y322102D03*
X533536Y330602D03*
X533636Y326402D03*
X526200Y326000D03*
G54D13*
X38109Y368733D03*
X542500Y263771D03*
X618000Y77300D03*
X617798Y408736D03*
X612798Y408636D03*
G54D31*
X607104Y387500D03*
X618566D03*
Y343800D03*
X607104D03*
G54D32*
G01X-4246Y-109426D02*
Y-189426D01*
G01D02*
X1290354D01*
G01X-4246Y-144926D02*
X1290354D01*
G01X-8246Y-93426D02*
G02I-12000J0D01*
G01X-13396D02*
G02I-6850J0D01*
G01X-20246Y-109426D02*
Y-77426D01*
G01X-4246Y-93426D02*
X-36246D01*
G01X-4246Y-109426D02*
X1290354D01*
G01X502854D02*
Y-189426D01*
G01X640354Y-109426D02*
Y-189426D01*
G01X755354Y-109426D02*
Y-189426D01*
G01X922854Y-109426D02*
Y-189426D01*
G01X1092854Y-109426D02*
Y-189426D01*
G01X1290354Y-109426D02*
Y-189426D01*
G01X1318354Y-93426D02*
G02I-12000J0D01*
G01X1313204D02*
G02I-6850J0D01*
G01X1306354Y-109426D02*
Y-77426D01*
G01X1322354Y-93426D02*
X1290354D01*
G54D14*
X41309Y387463D03*
G54D23*
X52705Y355795D03*
X48325Y355850D03*
X57398Y355860D03*
G54D33*
G01X-43308Y-5685D02*
G03X-29308Y-19685I14000J0D01*
G01X85820D02*
X-29308D01*
G01X0Y3937D02*
Y106969D01*
G01X636457Y0D02*
X3937D01*
G01X0Y3937D02*
G03X3937Y0I3937J0D01*
G01Y-7874D02*
X77283D01*
G01X-7874Y3937D02*
G03X3937Y-7874I11811J0D01*
G01X-7874Y50259D02*
Y3937D01*
G01X-43308Y-5685D02*
Y103032D01*
G01X0Y3937D02*
G03X3937Y0I3937J0D01*
G01X0Y3937D02*
G03X3937Y0I3937J0D01*
G01X636457D02*
X3937D01*
G01X636457D02*
X3937D01*
G01X0Y3937D02*
Y106969D01*
G01Y3937D02*
Y106969D01*
G01Y50259D02*
G03X-7874I-3937J0D01*
G01Y75460D02*
G03X0I3937J0D01*
G01X-7874Y103032D02*
Y75456D01*
G01X-43307Y286142D02*
Y116811D01*
G01D02*
X-37402Y110906D01*
G01D02*
X-3937D01*
G01X0Y106969D02*
G03X-3937Y110906I-3937J0D01*
G01X-43308Y103032D02*
X-7874D01*
G01X0Y106969D02*
G03X-3937Y110906I-3937J0D01*
G01X0Y106969D02*
G03X-3937Y110906I-3937J0D01*
G01X-37402D02*
X-3937D01*
G01X-37402D02*
X-3937D01*
G01X-41339Y114843D02*
X-37402Y110906D01*
G01X-43307Y116811D02*
X-37402Y110906D01*
G01X-43307Y286142D02*
Y116811D01*
G01Y360039D02*
Y300709D01*
G01X-37402Y292047D02*
X-43307Y286142D01*
G01Y300709D02*
X-37402Y294803D01*
G01Y292047D02*
X-1378D01*
G01X-37402Y294803D02*
X-1378D01*
G01Y292047D02*
G03Y294803I0J1378D01*
G01Y292047D02*
G03Y294803I0J1378D01*
G01Y292047D02*
G03Y294803I0J1378D01*
G01X-37402D02*
X-1378D01*
G01X-37402D02*
X-1378D01*
G01X-12598Y292047D02*
X-1378D01*
G01X-37402D02*
X-1378D01*
G01X-12598D02*
X-37402D01*
G01X-41339Y298740D02*
X-37402Y294803D01*
G01X-43307Y300709D02*
X-37402Y294803D01*
G01Y292047D02*
X-43307Y286142D01*
G01X-37402Y292047D02*
X-41339Y288110D01*
G01X-43307Y360039D02*
Y300709D01*
G01X-37402Y365945D02*
X-43307Y360039D01*
G01X0Y369882D02*
Y468504D01*
G01X-3937Y365945D02*
X-37402D01*
G01X-3937D02*
G03X0Y369882I0J3937D01*
G01X-43308Y373820D02*
Y583347D01*
G01X-43307Y373819D02*
X-43308Y373820D01*
G01X-7874Y373819D02*
X-43307D01*
G01X-7874Y401397D02*
Y373819D01*
G01X-3937Y365945D02*
G03X0Y369882I0J3937D01*
G01X-3937Y365945D02*
G03X0Y369882I0J3937D01*
G01X-3937Y365945D02*
X-37402D01*
G01X-3937D02*
X-37402D01*
G01X0Y369882D02*
Y468504D01*
G01Y369882D02*
Y468504D01*
G01X-37402Y365945D02*
X-43307Y360039D01*
G01X-37402Y365945D02*
X-41339Y362008D01*
G01X-7874Y426594D02*
Y530574D01*
G01Y426594D02*
G03X0I3937J0D01*
G01Y401397D02*
G03X-7874I-3937J0D01*
G01X3937Y472441D02*
X636457D01*
G01X3937D02*
G03X0Y468504I0J-3937D01*
G01Y484252D02*
G03X3937Y480315I3937J0D01*
G01X0Y484252D02*
G03X3937Y480315I3937J0D01*
G01X636457D02*
X3937D01*
G01X636457D02*
X3937D01*
G01X0Y484252D02*
Y587283D01*
G01Y484252D02*
Y587283D01*
G01X3937Y472441D02*
G03X0Y468504I0J-3937D01*
G01X3937Y472441D02*
G03X0Y468504I0J-3937D01*
G01X3937Y472441D02*
X636457D01*
G01X3937D02*
X636457D01*
G01X0Y530574D02*
G03X-7874I-3937J0D01*
G01Y555771D02*
G03X0I3937J0D01*
G01X-7874Y583347D02*
Y555771D01*
G01X-43308Y583347D02*
X-7874D01*
G01X0Y587283D02*
G03X-3937Y591220I-3937J0D01*
G01X0Y587283D02*
G03X-3937Y591220I-3937J0D01*
G01X-37402D02*
X-3937D01*
G01X-37402D02*
X-3937D01*
G01X-41339Y595157D02*
X-37402Y591220D01*
G01X-43307Y597126D02*
X-37402Y591220D01*
G01X-43307Y766457D02*
Y597126D01*
G01X-1378Y772362D02*
G03Y775118I0J1378D01*
G01Y772362D02*
G03Y775118I0J1378D01*
G01X-37402D02*
X-1378D01*
G01X-37402D02*
X-1378D01*
G01X-12598Y772362D02*
X-1378D01*
G01X-37402D02*
X-1378D01*
G01X-12598D02*
X-37402D01*
G01X-41339Y779055D02*
X-37402Y775118D01*
G01X-43307Y781024D02*
X-37402Y775118D01*
G01Y772362D02*
X-43307Y766457D01*
G01X-37402Y772362D02*
X-41339Y768425D01*
G01X-43307Y840354D02*
Y781024D01*
G01X-37402Y846260D02*
X-43307Y840354D01*
G01X-37402Y846260D02*
X-41339Y842323D01*
G01X0Y881711D02*
G03X-7874I-3937J0D01*
G01X-43308Y854134D02*
Y958441D01*
G01X-7874Y854134D02*
X-43308D01*
G01X-7874Y881712D02*
Y854134D01*
G01X-3937Y846260D02*
G03X0Y850197I0J3937D01*
G01X-3937Y846260D02*
G03X0Y850197I0J3937D01*
G01X-3937Y846260D02*
X-37402D01*
G01X-3937D02*
X-37402D01*
G01X0Y850197D02*
Y948819D01*
G01Y850197D02*
Y948819D01*
G01X3937Y960630D02*
G03X-7874Y948819I0J-11811D01*
G01Y906909D02*
Y948819D01*
G01Y906909D02*
G03X0I3937J0D01*
G01X-29308Y972441D02*
G03X-43308Y958441I0J-14000D01*
G01X3937Y952756D02*
G03X0Y948819I0J-3937D01*
G01X3937Y952756D02*
G03X0Y948819I0J-3937D01*
G01X3937Y952756D02*
X636457D01*
G01X3937D02*
X636457D01*
G01X3937Y960630D02*
X77283D01*
G01X-29308Y972441D02*
X1317968D01*
G01X121969Y-179426D02*
Y-161926D01*
G01X131139D02*
Y-179426D01*
G01Y-170676D02*
X121969D01*
G01X144054Y-179426D02*
X142744Y-179134D01*
X141434Y-177968D01*
X140560Y-175926D01*
X140124Y-173593D01*
X140560Y-171259D01*
X141434Y-169218D01*
X142744Y-168051D01*
X144054Y-167760D01*
X145364Y-168051D01*
X146674Y-169218D01*
X147547Y-171259D01*
X147766Y-173593D01*
X147547Y-175926D01*
X146674Y-177968D01*
X145364Y-179134D01*
X144054Y-179426D01*
G01X157842D02*
Y-167760D01*
G01Y-170676D02*
X158716Y-169218D01*
X160026Y-168051D01*
X161772Y-167760D01*
X163300Y-168051D01*
X164611Y-169218D01*
X165266Y-171259D01*
Y-179426D01*
G01X175779Y-171551D02*
X182766D01*
X182111Y-169509D01*
X181019Y-168343D01*
X179491Y-167760D01*
X177962Y-168051D01*
X176652Y-168926D01*
X175779Y-170968D01*
X175342Y-172718D01*
Y-174468D01*
X175779Y-176218D01*
X176871Y-177968D01*
X178181Y-179134D01*
X179709Y-179426D01*
X181237Y-178843D01*
X182766Y-177093D01*
G01X191969Y-184676D02*
X193279Y-185259D01*
X195026Y-184676D01*
X196117Y-183510D01*
X196991Y-182051D01*
X198300Y-177385D01*
X201139Y-167760D01*
G01X194152D02*
X198300Y-177385D01*
G01X233300Y-170093D02*
X234174Y-169218D01*
X234829Y-167760D01*
X235266Y-165717D01*
X234829Y-163968D01*
X233956Y-162801D01*
X232427Y-161926D01*
X226532D01*
Y-179426D01*
X233737D01*
X235266Y-178260D01*
X236139Y-176509D01*
X236576Y-174468D01*
X236139Y-172426D01*
X234829Y-170676D01*
X233300Y-170093D01*
X226532D01*
G01X252984Y-179426D02*
Y-167760D01*
G01Y-169801D02*
X252111Y-168635D01*
X250800Y-168051D01*
X249272Y-167760D01*
X247744Y-168343D01*
X246434Y-169509D01*
X245560Y-171259D01*
X245124Y-173593D01*
X245560Y-175926D01*
X246434Y-177676D01*
X247744Y-178843D01*
X249272Y-179426D01*
X250800Y-179134D01*
X252111Y-178260D01*
X252984Y-177093D01*
G01X270484Y-161926D02*
Y-179426D01*
G01Y-176802D02*
X269611Y-178260D01*
X268300Y-179134D01*
X266772Y-179426D01*
X265026Y-178843D01*
X263716Y-177385D01*
X262842Y-175635D01*
X262624Y-173593D01*
X262842Y-171551D01*
X263716Y-169801D01*
X265026Y-168343D01*
X266772Y-167760D01*
X268300Y-168051D01*
X269392Y-168635D01*
X270484Y-169801D01*
G01X280997Y-183801D02*
X282526Y-184968D01*
X284272Y-185259D01*
X285800Y-184968D01*
X287111Y-183510D01*
X287984Y-181468D01*
Y-167760D01*
G01Y-170093D02*
X287111Y-168926D01*
X285800Y-168051D01*
X284272Y-167760D01*
X282526Y-168343D01*
X281434Y-169509D01*
X280560Y-171551D01*
X280124Y-173593D01*
X280342Y-175343D01*
X281216Y-177385D01*
X282526Y-178843D01*
X284272Y-179426D01*
X285582Y-179134D01*
X287111Y-177968D01*
X287984Y-176802D01*
G01X298279Y-171551D02*
X305266D01*
X304611Y-169509D01*
X303519Y-168343D01*
X301991Y-167760D01*
X300462Y-168051D01*
X299152Y-168926D01*
X298279Y-170968D01*
X297842Y-172718D01*
Y-174468D01*
X298279Y-176218D01*
X299371Y-177968D01*
X300681Y-179134D01*
X302209Y-179426D01*
X303737Y-178843D01*
X305266Y-177093D01*
G01X315997Y-179426D02*
Y-167760D01*
G01Y-170093D02*
X317089Y-168926D01*
X318181Y-168051D01*
X319709Y-167760D01*
X320800Y-168051D01*
X322111Y-168926D01*
G01X349687Y-179426D02*
Y-161926D01*
X354927D01*
X356674Y-162801D01*
X357984Y-164843D01*
X358421Y-167176D01*
X357984Y-169509D01*
X356892Y-171259D01*
X354927Y-172135D01*
X349687D01*
G01X371554Y-161926D02*
Y-179426D01*
G01X366532Y-161926D02*
X376576D01*
G01X390800Y-170093D02*
X391674Y-169218D01*
X392329Y-167760D01*
X392766Y-165717D01*
X392329Y-163968D01*
X391456Y-162801D01*
X389927Y-161926D01*
X384032D01*
Y-179426D01*
X391237D01*
X392766Y-178260D01*
X393639Y-176509D01*
X394076Y-174468D01*
X393639Y-172426D01*
X392329Y-170676D01*
X390800Y-170093D01*
X384032D01*
G01X93694Y-19685D02*
G03X85820I-3937J0D01*
G01X93694D02*
X1317968D01*
G01X77283Y-7874D02*
G03Y0I0J3937D01*
G01X107993D02*
G03Y-7874I0J-3937D01*
G01D02*
X304843D01*
G01X77283Y472441D02*
G03Y480315I0J3937D01*
G01X107993D02*
G03Y472441I0J-3937D01*
G01X77283Y952756D02*
G03Y960630I0J3937D01*
G01X107993D02*
G03Y952756I0J-3937D01*
G01Y960630D02*
X304843D01*
G01X208377Y-134426D02*
Y-116926D01*
X214054Y-131509D01*
X219731Y-116926D01*
Y-134426D01*
G01X231554D02*
X230244Y-134134D01*
X228934Y-132968D01*
X228060Y-130926D01*
X227624Y-128593D01*
X228060Y-126259D01*
X228934Y-124218D01*
X230244Y-123051D01*
X231554Y-122760D01*
X232864Y-123051D01*
X234174Y-124218D01*
X235047Y-126259D01*
X235266Y-128593D01*
X235047Y-130926D01*
X234174Y-132968D01*
X232864Y-134134D01*
X231554Y-134426D01*
G01X252984Y-116926D02*
Y-134426D01*
G01Y-131802D02*
X252111Y-133260D01*
X250800Y-134134D01*
X249272Y-134426D01*
X247526Y-133843D01*
X246216Y-132385D01*
X245342Y-130635D01*
X245124Y-128593D01*
X245342Y-126551D01*
X246216Y-124801D01*
X247526Y-123343D01*
X249272Y-122760D01*
X250800Y-123051D01*
X251892Y-123635D01*
X252984Y-124801D01*
G01X263279Y-126551D02*
X270266D01*
X269611Y-124509D01*
X268519Y-123343D01*
X266991Y-122760D01*
X265462Y-123051D01*
X264152Y-123926D01*
X263279Y-125968D01*
X262842Y-127718D01*
Y-129468D01*
X263279Y-131218D01*
X264371Y-132968D01*
X265681Y-134134D01*
X267209Y-134426D01*
X268737Y-133843D01*
X270266Y-132093D01*
G01X284054Y-134426D02*
Y-116926D01*
G01X335552Y0D02*
G03Y-7874I0J-3937D01*
G01X304843D02*
G03Y0I0J3937D01*
G01X335552Y-7874D02*
X532402D01*
G01X304843Y472441D02*
G03Y480315I0J3937D01*
G01X335552D02*
G03Y472441I0J-3937D01*
G01Y960630D02*
G03Y952756I0J-3937D01*
G01X304843D02*
G03Y960630I0J3937D01*
G01X335552D02*
X532402D01*
G01X536554Y-179426D02*
Y-161926D01*
X533934Y-165426D01*
G01Y-179426D02*
X539174D01*
G01X556674D02*
Y-161926D01*
X548595Y-174468D01*
X559513D01*
G01X567406Y-172135D02*
X568934Y-170093D01*
X570244Y-168926D01*
X571991Y-168343D01*
X573519Y-168926D01*
X574611Y-170093D01*
X575484Y-171843D01*
X575702Y-173884D01*
X575484Y-175635D01*
X574611Y-177385D01*
X573300Y-178843D01*
X571772Y-179426D01*
X570026Y-178843D01*
X568497Y-177093D01*
X567624Y-174468D01*
X567406Y-171551D01*
X567842Y-167760D01*
X568497Y-165717D01*
X569589Y-163676D01*
X571117Y-162218D01*
X572646Y-161926D01*
X574174Y-162509D01*
X575266Y-163968D01*
G01X584906Y-164843D02*
X586216Y-163093D01*
X587744Y-162218D01*
X589491Y-161926D01*
X591674Y-162509D01*
X593202Y-163968D01*
X593639Y-165717D01*
X593421Y-167468D01*
X592547Y-168926D01*
X588181Y-171843D01*
X586216Y-173884D01*
X584906Y-176802D01*
X584469Y-179426D01*
X593639D01*
G01X602842Y-177385D02*
X604371Y-178843D01*
X606117Y-179426D01*
X607864Y-178843D01*
X609392Y-177093D01*
X610484Y-174468D01*
X610921Y-171843D01*
Y-168635D01*
X610484Y-166010D01*
X609392Y-163676D01*
X608082Y-162509D01*
X606554Y-161926D01*
X604807Y-162509D01*
X603497Y-163676D01*
X602624Y-165426D01*
X602187Y-167760D01*
X602624Y-169801D01*
X603716Y-171843D01*
X605026Y-173010D01*
X606554Y-173301D01*
X608300Y-172718D01*
X609611Y-171259D01*
X610921Y-168635D01*
G01X523437Y-134426D02*
Y-116926D01*
X528677D01*
X530424Y-117801D01*
X531734Y-119843D01*
X532171Y-122176D01*
X531734Y-124509D01*
X530642Y-126259D01*
X528677Y-127135D01*
X523437D01*
G01X550107Y-118385D02*
X548797Y-117509D01*
X547269Y-116926D01*
X545522D01*
X543557Y-117801D01*
X542029Y-119259D01*
X540937Y-121010D01*
X540064Y-123926D01*
X539845Y-126551D01*
X540282Y-129176D01*
X540937Y-130926D01*
X542247Y-132676D01*
X543776Y-133843D01*
X545304Y-134426D01*
X546832D01*
X548361Y-133843D01*
X549671Y-132968D01*
X550763Y-131802D01*
G01X564550Y-125093D02*
X565424Y-124218D01*
X566079Y-122760D01*
X566516Y-120717D01*
X566079Y-118968D01*
X565206Y-117801D01*
X563677Y-116926D01*
X557782D01*
Y-134426D01*
X564987D01*
X566516Y-133260D01*
X567389Y-131509D01*
X567826Y-129468D01*
X567389Y-127426D01*
X566079Y-125676D01*
X564550Y-125093D01*
X557782D01*
G01X573754Y-140259D02*
X586854D01*
G01X592782Y-134426D02*
Y-116926D01*
X602826Y-134426D01*
Y-116926D01*
G01X615304Y-134426D02*
X613557Y-134134D01*
X612029Y-132968D01*
X610719Y-131218D01*
X609845Y-129176D01*
X609409Y-126843D01*
Y-124509D01*
X609845Y-122176D01*
X610719Y-120134D01*
X612029Y-118385D01*
X613557Y-117218D01*
X615304Y-116926D01*
X617050Y-117218D01*
X618579Y-118385D01*
X619889Y-120134D01*
X620763Y-122176D01*
X621199Y-124509D01*
Y-126843D01*
X620763Y-129176D01*
X619889Y-131218D01*
X618579Y-132968D01*
X617050Y-134134D01*
X615304Y-134426D01*
G01X532402Y-7874D02*
G03Y0I0J3937D01*
G01X563111D02*
G03Y-7874I0J-3937D01*
G01D02*
X725552D01*
G01X627391Y353740D02*
X545906D01*
G01X627391Y378543D02*
X545906D01*
G01X541969Y357677D02*
Y374606D01*
G01Y357677D02*
G03X545906Y353740I3937J0D01*
G01Y378543D02*
G03X541969Y374606I0J-3937D01*
G01X545906Y378543D02*
G03X541969Y374606I0J-3937D01*
G01Y357677D02*
G03X545906Y353740I3937J0D01*
G01X541969Y357677D02*
G03X545906Y353740I3937J0D01*
G01Y378543D02*
G03X541969Y374606I0J-3937D01*
G01Y357677D02*
Y374606D01*
G01Y357677D02*
Y374606D01*
G01X627391Y378543D02*
X545906D01*
G01X627391D02*
X545906D01*
G01X627391Y353740D02*
X545906D01*
G01X627391D02*
X545906D01*
G01X532402Y472441D02*
G03Y480315I0J3937D01*
G01X563111D02*
G03Y472441I0J-3937D01*
G01X541969Y837992D02*
G03X545906Y834055I3937J0D01*
G01X541969Y837992D02*
G03X545906Y834055I3937J0D01*
G01X541969Y837992D02*
Y854921D01*
G01Y837992D02*
Y854921D01*
G01X627391Y834055D02*
X545906D01*
G01X627391D02*
X545906D01*
G01Y858858D02*
G03X541969Y854921I0J-3937D01*
G01X545906Y858858D02*
G03X541969Y854921I0J-3937D01*
G01X627391Y858858D02*
X545906D01*
G01X627391D02*
X545906D01*
G01X532402Y952756D02*
G03Y960630I0J3937D01*
G01X563111D02*
G03Y952756I0J-3937D01*
G01Y960630D02*
X725552D01*
G01X636457Y132035D02*
X624646D01*
G01X620709Y135972D02*
G03X622675Y132564I3937J0D01*
G01X622709Y132545D02*
G03X624646Y132035I1938J3427D01*
G01X622675Y132564D02*
G03X622709Y132545I1937J3427D01*
G01X622675Y132564D02*
G03X624646Y132035I1971J3409D01*
G01X620709Y135972D02*
G03X622675Y132564I3937J0D01*
G01X620709Y135972D02*
G03X622708Y132545I3937J0D01*
G01X620709Y135972D02*
Y312846D01*
G01Y135972D02*
Y312846D01*
G01X622675Y132564D02*
G03X624646Y132035I1971J3409D01*
G01X622708Y132545D02*
G03X624646Y132035I1938J3427D01*
G01X620709Y135972D02*
G03X622675Y132564I3937J0D01*
G01X620709Y135972D02*
G03X622708Y132545I3937J0D01*
G01X620709Y135972D02*
Y312846D01*
G01Y135972D02*
Y312846D01*
G01X636457Y132035D02*
X624646D01*
G01X636457D02*
X624646D01*
G01X636457Y316783D02*
X624646D01*
G01X622675Y316255D02*
G03X620709Y312846I1971J-3408D01*
G01X624646Y316783D02*
G03X622709Y316274I-1J-3937D01*
G01D02*
G03X622675Y316255I1904J-3446D01*
G01X624646Y316783D02*
G03X622675Y316255I-1J-3937D01*
G01D02*
G03X620709Y312846I1971J-3408D01*
G01X622708Y316274D02*
G03X620709Y312846I1938J-3427D01*
G01X624646Y316783D02*
G03X622675Y316255I-1J-3937D01*
G01X624646Y316783D02*
G03X622708Y316274I-2J-3937D01*
G01X622675Y316255D02*
G03X620709Y312846I1971J-3408D01*
G01X622708Y316274D02*
G03X620709Y312846I1938J-3427D01*
G01X636457Y316783D02*
X624646D01*
G01X636457D02*
X624646D01*
G01X620709Y312657D02*
Y311161D01*
G01X629575Y379204D02*
X638641Y385248D01*
G01Y347035D02*
X629575Y353079D01*
G01D02*
G03X627391Y353740I-2184J-3276D01*
G01Y378543D02*
G03X629575Y379204I0J3937D01*
G01X627391Y378543D02*
G03X629574Y379205I-2J3937D01*
G01X627391Y378543D02*
G03X629574Y379205I-2J3937D01*
G01Y353079D02*
G03X627391Y353740I-2184J-3276D01*
G01X629574Y353079D02*
G03X627391Y353740I-2184J-3276D01*
G01X638641Y347035D02*
X629574Y353079D01*
G01X638641Y347035D02*
X629574Y353079D01*
G01Y379204D02*
X638641Y385248D01*
G01X629574Y379204D02*
X638641Y385248D01*
G01X622675Y612879D02*
G03X624646Y612350I1971J3409D01*
G01X622708Y612860D02*
G03X624646Y612350I1938J3427D01*
G01X620709Y616287D02*
G03X622675Y612879I3937J0D01*
G01X620709Y616287D02*
G03X622708Y612860I3937J0D01*
G01X620709Y616287D02*
Y793161D01*
G01Y616287D02*
Y793161D01*
G01X636457Y612350D02*
X624646D01*
G01X636457D02*
X624646D01*
G01Y797098D02*
G03X622675Y796570I-1J-3937D01*
G01X624646Y797098D02*
G03X622708Y796589I-2J-3937D01*
G01X622675Y796570D02*
G03X620709Y793161I1971J-3408D01*
G01X622708Y796589D02*
G03X620709Y793161I1938J-3427D01*
G01X636457Y797098D02*
X624646D01*
G01X636457D02*
X624646D01*
G01X629574Y833394D02*
G03X627391Y834055I-2184J-3276D01*
G01X629574Y833394D02*
G03X627391Y834055I-2184J-3276D01*
G01X638641Y827350D02*
X629574Y833394D01*
G01X638641Y827350D02*
X629574Y833394D01*
G01X627391Y858858D02*
G03X629574Y859520I-2J3937D01*
G01X627391Y858858D02*
G03X629574Y859520I-2J3937D01*
G01D02*
X638641Y865563D01*
G01X629574Y859520D02*
X638641Y865563D01*
G01X689104Y-179426D02*
Y-161926D01*
X686484Y-165426D01*
G01Y-179426D02*
X691724D01*
G01X701145D02*
X706604Y-161926D01*
X712063Y-179426D01*
G01X710097Y-173301D02*
X703110D01*
G01X666145Y-116926D02*
X671604Y-134426D01*
X677063Y-116926D01*
G01X693471Y-134426D02*
X684737D01*
Y-116926D01*
X693471D01*
G01X689977Y-125384D02*
X684737D01*
G01X702237Y-134426D02*
Y-116926D01*
X707696D01*
X709442Y-117801D01*
X710534Y-118968D01*
X710971Y-121301D01*
X710534Y-123635D01*
X709224Y-125093D01*
X707696Y-125968D01*
X702237D01*
G01X707696D02*
X710971Y-134426D01*
G01X724104Y-135009D02*
X723667Y-134718D01*
Y-134134D01*
X724104Y-133843D01*
X724541Y-134134D01*
Y-134718D01*
X724104Y-135009D01*
G01X640394Y128098D02*
Y3937D01*
G01X636457Y0D02*
G03X640394Y3937I0J3937D01*
G01Y128098D02*
Y3937D01*
G01Y128098D02*
Y3937D01*
G01X648267Y34437D02*
G03X640393I-3937J0D01*
G01X648266Y3937D02*
G03X652203Y0I3937J0D01*
G01X648266Y3937D02*
G03X652203Y0I3937J0D01*
G01X648266Y3937D02*
Y83917D01*
G01Y3937D02*
Y83917D01*
G01X1284723Y0D02*
X652203D01*
G01X1284723D02*
X652203D01*
G01X636457D02*
G03X640394Y3937I0J3937D01*
G01X636457Y0D02*
G03X640394Y3937I0J3937D01*
G01Y112350D02*
Y3937D01*
G01Y112350D02*
Y3937D01*
G01X640393Y65146D02*
G03X648267I3937J0D01*
G01X650019Y87193D02*
G03X648266Y83917I2185J-3276D01*
G01X661269Y93898D02*
G03X659085Y93237I0J-3937D01*
G01X661269Y93898D02*
G03X659085Y93237I0J-3937D01*
G01X650019Y87193D02*
G03X648266Y83917I2185J-3276D01*
G01X661269Y93898D02*
X742754D01*
G01X661269D02*
X742754D01*
G01X659085Y93237D02*
X650019Y87193D01*
G01X659085Y93237D02*
X650019Y87193D01*
G01X640394Y128098D02*
G03X636457Y132035I-3937J0D01*
G01X664014Y155657D02*
G03X665985Y156186I0J3938D01*
G01X652203Y155657D02*
G03X648266Y151720I0J-3937D01*
G01X652203Y155657D02*
G03X648266Y151720I0J-3937D01*
G01X664014Y155657D02*
G03X665952Y156167I0J3937D01*
G01X665985Y156186D02*
G03X667951Y159594I-1971J3408D01*
G01X665952Y156167D02*
G03X667951Y159594I-1938J3427D01*
G01X648266Y128682D02*
Y151720D01*
G01Y128682D02*
Y151720D01*
G01X667951Y336469D02*
Y159594D01*
G01Y336469D02*
Y159594D01*
G01X652203Y155657D02*
X664014D01*
G01X652203D02*
X664014D01*
G01X640394Y128098D02*
G03X636457Y132035I-3937J0D01*
G01X640394Y128098D02*
G03X636457Y132035I-3937J0D01*
G01X659085Y119362D02*
G03X661269Y118701I2184J3276D01*
G01X648266Y128682D02*
G03X650019Y125406I3937J0D01*
G01X648266Y128682D02*
G03X650019Y125406I3937J0D01*
G01X659085Y119362D02*
G03X661269Y118701I2184J3276D01*
G01X650019Y125406D02*
X659085Y119362D01*
G01X650019Y125406D02*
X659085Y119362D01*
G01X661269Y118701D02*
X742754D01*
G01X661269D02*
X742754D01*
G01X640394Y343759D02*
Y320720D01*
G01X636457Y316783D02*
G03X640394Y320720I0J3937D01*
G01X636457Y316783D02*
G03X640394Y320720I0J3937D01*
G01X636457Y316783D02*
G03X640394Y320720I0J3937D01*
G01Y343759D02*
Y320720D01*
G01Y343759D02*
Y320720D01*
G01Y388524D02*
Y421048D01*
G01Y343759D02*
G03X638641Y347035I-3937J0D01*
G01Y385248D02*
G03X640394Y388524I-2184J3276D01*
G01X665985Y339877D02*
G03X664014Y340406I-1971J-3409D01*
G01X648266Y344343D02*
G03X652203Y340406I3937J0D01*
G01X665952Y339896D02*
G03X664014Y340406I-1938J-3427D01*
G01X648266Y344343D02*
G03X652203Y340406I3937J0D01*
G01X667951Y336469D02*
G03X665985Y339877I-3937J0D01*
G01X667951Y336469D02*
G03X665952Y339896I-3937J0D01*
G01X648266Y344343D02*
Y468504D01*
G01Y344343D02*
Y468504D01*
G01X652203Y340406D02*
X664014D01*
G01X652203D02*
X664014D01*
G01X648266Y360091D02*
Y468504D01*
G01Y360091D02*
Y468504D01*
G01X638641Y385248D02*
G03X640394Y388524I-2185J3276D01*
G01X638641Y385248D02*
G03X640394Y388524I-2185J3276D01*
G01Y343759D02*
G03X638641Y347035I-3937J0D01*
G01X640394Y343759D02*
G03X638641Y347035I-3937J0D01*
G01X640394Y468504D02*
Y388524D01*
G01Y468504D02*
Y388524D01*
G01Y421048D02*
Y445094D01*
G01D02*
Y468504D01*
G01X640393Y438004D02*
G03X648267I3937J0D01*
G01Y407295D02*
G03X640393I-3937J0D01*
G01X640394Y468504D02*
G03X636457Y472441I-3937J0D01*
G01X640394Y608413D02*
Y484252D01*
G01Y608413D02*
Y484252D01*
G01X652203Y472441D02*
G03X648266Y468504I0J-3937D01*
G01X652203Y472441D02*
G03X648266Y468504I0J-3937D01*
G01X652203Y472441D02*
X1284723D01*
G01X652203D02*
X1284723D01*
G01X648266Y484252D02*
G03X652203Y480315I3937J0D01*
G01X648266Y484252D02*
G03X652203Y480315I3937J0D01*
G01X648266Y484252D02*
Y564231D01*
G01Y484252D02*
Y564231D01*
G01X1284723Y480315D02*
X652203D01*
G01X1284723D02*
X652203D01*
G01X636457D02*
G03X640394Y484252I0J3937D01*
G01X636457Y480315D02*
G03X640394Y484252I0J3937D01*
G01Y592665D02*
Y484252D01*
G01Y592665D02*
Y484252D01*
G01Y468504D02*
G03X636457Y472441I-3937J0D01*
G01X640394Y468504D02*
G03X636457Y472441I-3937J0D01*
G01X648267Y514753D02*
G03X640393I-3937J0D01*
G01Y545462D02*
G03X648267I3937J0D01*
G01X648266Y608997D02*
Y632035D01*
G01Y608997D02*
Y632035D01*
G01X640394Y608413D02*
G03X636457Y612350I-3937J0D01*
G01X640394Y608413D02*
G03X636457Y612350I-3937J0D01*
G01X650019Y567507D02*
G03X648266Y564231I2184J-3276D01*
G01X661269Y574213D02*
G03X659085Y573552I0J-3937D01*
G01X661269Y574213D02*
G03X659085Y573552I0J-3937D01*
G01X650019Y567507D02*
G03X648266Y564231I2184J-3276D01*
G01X659085Y599677D02*
G03X661269Y599016I2184J3276D01*
G01X648266Y608997D02*
G03X650019Y605721I3937J0D01*
G01X648266Y608997D02*
G03X650019Y605721I3937J0D01*
G01X659085Y599677D02*
G03X661269Y599016I2184J3276D01*
G01X650019Y605721D02*
X659085Y599677D01*
G01X650019Y605721D02*
X659085Y599677D01*
G01X661269Y574213D02*
X742754D01*
G01X661269D02*
X742754D01*
G01X661269Y599016D02*
X742754D01*
G01X661269D02*
X742754D01*
G01X659085Y573552D02*
X650019Y567507D01*
G01X659085Y573552D02*
X650019Y567507D01*
G01X664014Y635972D02*
G03X665985Y636501I0J3938D01*
G01X652203Y635972D02*
G03X648266Y632035I0J-3937D01*
G01X652203Y635972D02*
G03X648266Y632035I0J-3937D01*
G01X664014Y635972D02*
G03X665952Y636482I0J3937D01*
G01X665985Y636501D02*
G03X667951Y639909I-1971J3408D01*
G01X665952Y636482D02*
G03X667951Y639909I-1938J3427D01*
G01Y816783D02*
Y639909D01*
G01Y816783D02*
Y639909D01*
G01X652203Y635972D02*
X664014D01*
G01X652203D02*
X664014D01*
G01X665985Y820192D02*
G03X664014Y820720I-1970J-3409D01*
G01X648266Y824657D02*
G03X652203Y820720I3937J0D01*
G01X665952Y820211D02*
G03X664014Y820720I-1936J-3428D01*
G01X648266Y824657D02*
G03X652203Y820720I3937J0D01*
G01X667951Y816783D02*
G03X665985Y820192I-3937J1D01*
G01X667951Y816783D02*
G03X665952Y820211I-3937J1D01*
G01X648266Y824657D02*
Y948819D01*
G01Y824657D02*
Y948819D01*
G01X652203Y820720D02*
X664014D01*
G01X652203D02*
X664014D01*
G01X636457Y797098D02*
G03X640394Y801035I0J3937D01*
G01X636457Y797098D02*
G03X640394Y801035I0J3937D01*
G01Y824074D02*
Y801035D01*
G01Y824074D02*
Y801035D01*
G01X648266Y840406D02*
Y948819D01*
G01Y840406D02*
Y948819D01*
G01X640394Y824074D02*
G03X638641Y827350I-3938J0D01*
G01X640394Y824074D02*
G03X638641Y827350I-3938J0D01*
G01X648267Y887611D02*
G03X640393I-3937J0D01*
G01X638641Y865563D02*
G03X640394Y868839I-2185J3276D01*
G01X638641Y865563D02*
G03X640394Y868839I-2185J3276D01*
G01Y948819D02*
Y868839D01*
G01Y948819D02*
Y868839D01*
G01X640393Y918320D02*
G03X648267I3937J0D01*
G01X652203Y952756D02*
G03X648266Y948819I0J-3937D01*
G01X652203Y952756D02*
G03X648266Y948819I0J-3937D01*
G01X652203Y952756D02*
X1284723D01*
G01X652203D02*
X1284723D01*
G01X640394Y948819D02*
G03X636457Y952756I-3937J0D01*
G01X640394Y948819D02*
G03X636457Y952756I-3937J0D01*
G01X725552Y-7874D02*
G03Y0I0J3937D01*
G01X742754Y93898D02*
G03X746691Y97835I0J3937D01*
G01X742754Y93898D02*
G03X746691Y97835I0J3937D01*
G01Y114764D02*
Y97835D01*
G01Y114764D02*
Y97835D01*
G01Y114764D02*
G03X742754Y118701I-3937J0D01*
G01X746691Y114764D02*
G03X742754Y118701I-3937J0D01*
G01X725552Y472441D02*
G03Y480315I0J3937D01*
G01X742754Y574213D02*
G03X746691Y578150I0J3937D01*
G01Y595079D02*
G03X742754Y599016I-3937J0D01*
G01X746691Y595079D02*
G03X742754Y599016I-3937J0D01*
G01Y574213D02*
G03X746691Y578150I0J3937D01*
G01Y595079D02*
Y578150D01*
G01Y595079D02*
Y578150D01*
G01X725552Y952756D02*
G03Y960630I0J3937D01*
G01X790937Y-116926D02*
Y-134426D01*
X799671D01*
G01X816734D02*
Y-122760D01*
G01Y-124801D02*
X815861Y-123635D01*
X814550Y-123051D01*
X813022Y-122760D01*
X811494Y-123343D01*
X810184Y-124509D01*
X809310Y-126259D01*
X808874Y-128593D01*
X809310Y-130926D01*
X810184Y-132676D01*
X811494Y-133843D01*
X813022Y-134426D01*
X814550Y-134134D01*
X815861Y-133260D01*
X816734Y-132093D01*
G01X825719Y-139676D02*
X827029Y-140259D01*
X828776Y-139676D01*
X829867Y-138510D01*
X830741Y-137051D01*
X832050Y-132385D01*
X834889Y-122760D01*
G01X827902D02*
X832050Y-132385D01*
G01X844529Y-126551D02*
X851516D01*
X850861Y-124509D01*
X849769Y-123343D01*
X848241Y-122760D01*
X846712Y-123051D01*
X845402Y-123926D01*
X844529Y-125968D01*
X844092Y-127718D01*
Y-129468D01*
X844529Y-131218D01*
X845621Y-132968D01*
X846931Y-134134D01*
X848459Y-134426D01*
X849987Y-133843D01*
X851516Y-132093D01*
G01X862247Y-134426D02*
Y-122760D01*
G01Y-125093D02*
X863339Y-123926D01*
X864431Y-123051D01*
X865959Y-122760D01*
X867050Y-123051D01*
X868361Y-123926D01*
G01X879529Y-132385D02*
X880621Y-133551D01*
X882149Y-134426D01*
X883459D01*
X884769Y-133843D01*
X885642Y-132968D01*
X886079Y-131802D01*
X885861Y-130051D01*
X884987Y-129176D01*
X881057Y-127426D01*
X880184Y-125384D01*
X880621Y-123926D01*
X881494Y-123051D01*
X882804Y-122760D01*
X884114Y-123051D01*
X885424Y-123926D01*
G01X953111Y-7874D02*
X756261D01*
G01Y0D02*
G03Y-7874I0J-3937D01*
G01Y480315D02*
G03Y472441I0J-3937D01*
G01Y960630D02*
G03Y952756I0J-3937D01*
G01X953111Y960630D02*
X756261D01*
G01X812804Y-161926D02*
Y-179426D01*
G01X807782Y-161926D02*
X817826D01*
G01X825719Y-177093D02*
X827466Y-178551D01*
X829431Y-179426D01*
X831177D01*
X832924Y-178551D01*
X834234Y-177093D01*
X834889Y-175051D01*
X834452Y-173010D01*
X833361Y-171259D01*
X831396Y-170093D01*
X828776Y-169509D01*
X827247Y-168343D01*
X826592Y-166301D01*
X827029Y-164259D01*
X828121Y-162801D01*
X829649Y-161926D01*
X831177D01*
X832706Y-162509D01*
X834016Y-163968D01*
G01X842127Y-179426D02*
Y-161926D01*
X847804Y-176509D01*
X853481Y-161926D01*
Y-179426D01*
G01X860501D02*
Y-161926D01*
X864867D01*
X866614Y-162801D01*
X867924Y-163968D01*
X869016Y-165717D01*
X869889Y-167760D01*
X870107Y-170676D01*
X869889Y-173593D01*
X869016Y-175635D01*
X867924Y-177385D01*
X866614Y-178551D01*
X864867Y-179426D01*
X860501D01*
G01X924737Y-175926D02*
X925829Y-177676D01*
X927139Y-178843D01*
X928667Y-179426D01*
X930414Y-178843D01*
X931724Y-177676D01*
X933034Y-175926D01*
X933471Y-173593D01*
Y-161926D01*
G01X946604Y-179426D02*
X944857Y-179134D01*
X943329Y-177968D01*
X942019Y-176218D01*
X941145Y-174176D01*
X940709Y-171843D01*
Y-169509D01*
X941145Y-167176D01*
X942019Y-165134D01*
X943329Y-163385D01*
X944857Y-162218D01*
X946604Y-161926D01*
X948350Y-162218D01*
X949879Y-163385D01*
X951189Y-165134D01*
X952063Y-167176D01*
X952499Y-169509D01*
Y-171843D01*
X952063Y-174176D01*
X951189Y-176218D01*
X949879Y-177968D01*
X948350Y-179134D01*
X946604Y-179426D01*
G01X959519Y-177093D02*
X961266Y-178551D01*
X963231Y-179426D01*
X964977D01*
X966724Y-178551D01*
X968034Y-177093D01*
X968689Y-175051D01*
X968252Y-173010D01*
X967161Y-171259D01*
X965196Y-170093D01*
X962576Y-169509D01*
X961047Y-168343D01*
X960392Y-166301D01*
X960829Y-164259D01*
X961921Y-162801D01*
X963449Y-161926D01*
X964977D01*
X966506Y-162509D01*
X967816Y-163968D01*
G01X985971Y-179426D02*
X977237D01*
Y-161926D01*
X985971D01*
G01X982477Y-170384D02*
X977237D01*
G01X994737Y-179426D02*
Y-161926D01*
X999977D01*
X1001724Y-162801D01*
X1003034Y-164843D01*
X1003471Y-167176D01*
X1003034Y-169509D01*
X1001942Y-171259D01*
X999977Y-172135D01*
X994737D01*
G01X1012019Y-179426D02*
Y-161926D01*
G01X1021189D02*
Y-179426D01*
G01Y-170676D02*
X1012019D01*
G01X1047237Y-161926D02*
Y-179426D01*
X1055971D01*
G01X1063645D02*
X1069104Y-161926D01*
X1074563Y-179426D01*
G01X1072597Y-173301D02*
X1065610D01*
G01X1081801Y-161926D02*
Y-174468D01*
X1082674Y-177093D01*
X1084421Y-178843D01*
X1086604Y-179426D01*
X1088787Y-178843D01*
X1090534Y-177093D01*
X1091407Y-174468D01*
Y-161926D01*
G01X941801Y-134426D02*
Y-116926D01*
X946167D01*
X947914Y-117801D01*
X949224Y-118968D01*
X950316Y-120717D01*
X951189Y-122760D01*
X951407Y-125676D01*
X951189Y-128593D01*
X950316Y-130635D01*
X949224Y-132385D01*
X947914Y-133551D01*
X946167Y-134426D01*
X941801D01*
G01X960829Y-126551D02*
X967816D01*
X967161Y-124509D01*
X966069Y-123343D01*
X964541Y-122760D01*
X963012Y-123051D01*
X961702Y-123926D01*
X960829Y-125968D01*
X960392Y-127718D01*
Y-129468D01*
X960829Y-131218D01*
X961921Y-132968D01*
X963231Y-134134D01*
X964759Y-134426D01*
X966287Y-133843D01*
X967816Y-132093D01*
G01X978329Y-132385D02*
X979421Y-133551D01*
X980949Y-134426D01*
X982259D01*
X983569Y-133843D01*
X984442Y-132968D01*
X984879Y-131802D01*
X984661Y-130051D01*
X983787Y-129176D01*
X979857Y-127426D01*
X978984Y-125384D01*
X979421Y-123926D01*
X980294Y-123051D01*
X981604Y-122760D01*
X982914Y-123051D01*
X984224Y-123926D01*
G01X999104Y-122760D02*
Y-134426D01*
G01Y-118093D02*
X998667Y-117801D01*
Y-117218D01*
X999104Y-116926D01*
X999541Y-117218D01*
Y-117801D01*
X999104Y-118093D01*
G01X1013547Y-138801D02*
X1015076Y-139968D01*
X1016822Y-140259D01*
X1018350Y-139968D01*
X1019661Y-138510D01*
X1020534Y-136468D01*
Y-122760D01*
G01Y-125093D02*
X1019661Y-123926D01*
X1018350Y-123051D01*
X1016822Y-122760D01*
X1015076Y-123343D01*
X1013984Y-124509D01*
X1013110Y-126551D01*
X1012674Y-128593D01*
X1012892Y-130343D01*
X1013766Y-132385D01*
X1015076Y-133843D01*
X1016822Y-134426D01*
X1018132Y-134134D01*
X1019661Y-132968D01*
X1020534Y-131802D01*
G01X1030392Y-134426D02*
Y-122760D01*
G01Y-125676D02*
X1031266Y-124218D01*
X1032576Y-123051D01*
X1034322Y-122760D01*
X1035850Y-123051D01*
X1037161Y-124218D01*
X1037816Y-126259D01*
Y-134426D01*
G01X1048329Y-126551D02*
X1055316D01*
X1054661Y-124509D01*
X1053569Y-123343D01*
X1052041Y-122760D01*
X1050512Y-123051D01*
X1049202Y-123926D01*
X1048329Y-125968D01*
X1047892Y-127718D01*
Y-129468D01*
X1048329Y-131218D01*
X1049421Y-132968D01*
X1050731Y-134134D01*
X1052259Y-134426D01*
X1053787Y-133843D01*
X1055316Y-132093D01*
G01X1066047Y-134426D02*
Y-122760D01*
G01Y-125093D02*
X1067139Y-123926D01*
X1068231Y-123051D01*
X1069759Y-122760D01*
X1070850Y-123051D01*
X1072161Y-123926D01*
G01X953111Y-7874D02*
G03Y0I0J3937D01*
G01Y472441D02*
G03Y480315I0J3937D01*
G01Y952756D02*
G03Y960630I0J3937D01*
G01X1180670Y-7874D02*
X983820D01*
G01Y0D02*
G03Y-7874I0J-3937D01*
G01Y480315D02*
G03Y472441I0J-3937D01*
G01Y960630D02*
G03Y952756I0J-3937D01*
G01X1180670Y960630D02*
X983820D01*
G01X1112804Y-179426D02*
Y-161926D01*
X1110184Y-165426D01*
G01Y-179426D02*
X1115424D01*
G01X1130304D02*
Y-161926D01*
X1127684Y-165426D01*
G01Y-179426D02*
X1132924D01*
G01X1143874Y-180009D02*
X1151734Y-161926D01*
G01X1161156Y-164843D02*
X1162466Y-163093D01*
X1163994Y-162218D01*
X1165741Y-161926D01*
X1167924Y-162509D01*
X1169452Y-163968D01*
X1169889Y-165717D01*
X1169671Y-167468D01*
X1168797Y-168926D01*
X1164431Y-171843D01*
X1162466Y-173884D01*
X1161156Y-176802D01*
X1160719Y-179426D01*
X1169889D01*
G01X1178001Y-176802D02*
X1179310Y-178260D01*
X1180839Y-179134D01*
X1182804Y-179426D01*
X1184769Y-178843D01*
X1186297Y-177676D01*
X1187389Y-175635D01*
X1187607Y-173301D01*
X1187171Y-170968D01*
X1186079Y-169509D01*
X1184550Y-168343D01*
X1183022Y-168051D01*
X1181494Y-168343D01*
X1179529Y-169509D01*
X1180184Y-161926D01*
X1186079D01*
G01X1196374Y-180009D02*
X1204234Y-161926D01*
G01X1213656Y-164843D02*
X1214966Y-163093D01*
X1216494Y-162218D01*
X1218241Y-161926D01*
X1220424Y-162509D01*
X1221952Y-163968D01*
X1222389Y-165717D01*
X1222171Y-167468D01*
X1221297Y-168926D01*
X1216931Y-171843D01*
X1214966Y-173884D01*
X1213656Y-176802D01*
X1213219Y-179426D01*
X1222389D01*
G01X1235304Y-161926D02*
X1233557Y-162509D01*
X1232247Y-163968D01*
X1231374Y-165717D01*
X1230719Y-168051D01*
X1230501Y-170676D01*
X1230719Y-173301D01*
X1231374Y-175635D01*
X1232247Y-177385D01*
X1233557Y-178843D01*
X1235304Y-179426D01*
X1237050Y-178843D01*
X1238361Y-177385D01*
X1239234Y-175635D01*
X1239889Y-173301D01*
X1240107Y-170676D01*
X1239889Y-168051D01*
X1239234Y-165717D01*
X1238361Y-163968D01*
X1237050Y-162509D01*
X1235304Y-161926D01*
G01X1252804Y-179426D02*
Y-161926D01*
X1250184Y-165426D01*
G01Y-179426D02*
X1255424D01*
G01X1272924D02*
Y-161926D01*
X1264845Y-174468D01*
X1275763D01*
G01X1160501Y-134426D02*
Y-116926D01*
X1164867D01*
X1166614Y-117801D01*
X1167924Y-118968D01*
X1169016Y-120717D01*
X1169889Y-122760D01*
X1170107Y-125676D01*
X1169889Y-128593D01*
X1169016Y-130635D01*
X1167924Y-132385D01*
X1166614Y-133551D01*
X1164867Y-134426D01*
X1160501D01*
G01X1186734D02*
Y-122760D01*
G01Y-124801D02*
X1185861Y-123635D01*
X1184550Y-123051D01*
X1183022Y-122760D01*
X1181494Y-123343D01*
X1180184Y-124509D01*
X1179310Y-126259D01*
X1178874Y-128593D01*
X1179310Y-130926D01*
X1180184Y-132676D01*
X1181494Y-133843D01*
X1183022Y-134426D01*
X1184550Y-134134D01*
X1185861Y-133260D01*
X1186734Y-132093D01*
G01X1200304Y-116926D02*
Y-134426D01*
G01X1197247Y-122760D02*
X1203361D01*
G01X1214529Y-126551D02*
X1221516D01*
X1220861Y-124509D01*
X1219769Y-123343D01*
X1218241Y-122760D01*
X1216712Y-123051D01*
X1215402Y-123926D01*
X1214529Y-125968D01*
X1214092Y-127718D01*
Y-129468D01*
X1214529Y-131218D01*
X1215621Y-132968D01*
X1216931Y-134134D01*
X1218459Y-134426D01*
X1219987Y-133843D01*
X1221516Y-132093D01*
G01X1180670Y-7874D02*
G03Y0I0J3937D01*
G01Y472441D02*
G03Y480315I0J3937D01*
G01Y952756D02*
G03Y960630I0J3937D01*
G01X1211380Y0D02*
G03Y-7874I0J-3937D01*
G01D02*
X1284723D01*
G01X1211380Y480315D02*
G03Y472441I0J-3937D01*
G01Y960630D02*
G03Y952756I0J-3937D01*
G01Y960630D02*
X1284723D01*
G01X1317968Y-19685D02*
G03X1331968Y-5685I0J14000D01*
G01X1296534Y45847D02*
G03X1288660I-3937J0D01*
G01X1296534Y3937D02*
Y45847D01*
G01X1284723Y-7874D02*
G03X1296534Y3937I0J11811D01*
G01X1284723Y0D02*
G03X1288660Y3937I0J3937D01*
G01X1284723Y0D02*
G03X1288660Y3937I0J3937D01*
G01Y102559D02*
Y3937D01*
G01Y102559D02*
Y3937D01*
G01Y71044D02*
G03X1296534I3937J0D01*
G01Y98622D02*
Y71044D01*
G01X1331968Y98622D02*
X1296534D01*
G01X1292597Y106496D02*
G03X1288660Y102559I0J-3937D01*
G01X1292597Y106496D02*
G03X1288660Y102559I0J-3937D01*
G01X1292597Y106496D02*
X1326061D01*
G01X1292597D02*
X1326061D01*
G01X1290038Y180394D02*
G03Y177638I0J-1378D01*
G01Y180394D02*
G03Y177638I0J-1378D01*
G01X1326061D02*
X1290038D01*
G01X1326061D02*
X1290038D01*
G01X1301258Y180394D02*
X1290038D01*
G01X1326061D02*
X1290038D01*
G01X1301258D02*
X1326061D01*
G01X1296534Y369409D02*
Y396985D01*
G01X1331968Y369409D02*
X1296534D01*
G01X1288660Y365472D02*
G03X1292597Y361535I3937J0D01*
G01X1288660Y365472D02*
G03X1292597Y361535I3937J0D01*
G01X1326061D02*
X1292597D01*
G01X1326061D02*
X1292597D01*
G01X1288660Y468504D02*
Y365472D01*
G01Y468504D02*
Y365472D01*
G01Y422182D02*
G03X1296534I3937J0D01*
G01Y526162D02*
Y422182D01*
G01Y396985D02*
G03X1288660I-3937J0D01*
G01Y468504D02*
G03X1284723Y472441I-3937J0D01*
G01X1288660Y468504D02*
G03X1284723Y472441I-3937J0D01*
G01Y480315D02*
G03X1288660Y484252I0J3937D01*
G01X1284723Y480315D02*
G03X1288660Y484252I0J3937D01*
G01Y582874D02*
Y484252D01*
G01Y582874D02*
Y484252D01*
G01X1296534Y526162D02*
G03X1288660I-3937J0D01*
G01Y551359D02*
G03X1296534I3937J0D01*
G01Y578937D02*
Y551359D01*
G01X1331968Y578937D02*
X1296534D01*
G01X1292597Y586811D02*
G03X1288660Y582874I0J-3937D01*
G01X1292597Y586811D02*
G03X1288660Y582874I0J-3937D01*
G01X1292597Y586811D02*
X1326061D01*
G01X1292597D02*
X1326061D01*
G01X1290038Y660709D02*
G03Y657953I0J-1378D01*
G01Y660709D02*
G03Y657953I0J-1378D01*
G01X1326061D02*
X1290038D01*
G01X1326061D02*
X1290038D01*
G01X1301258Y660709D02*
X1290038D01*
G01X1326061D02*
X1290038D01*
G01X1301258D02*
X1326061D01*
G01X1288660Y845787D02*
G03X1292597Y841850I3937J0D01*
G01X1288660Y845787D02*
G03X1292597Y841850I3937J0D01*
G01X1326061D02*
X1292597D01*
G01X1326061D02*
X1292597D01*
G01X1331968Y849724D02*
X1296534D01*
G01X1288660Y902497D02*
G03X1296534I3937J0D01*
G01Y948819D02*
Y902497D01*
G01Y877296D02*
G03X1288660I-3937J0D01*
G01X1296534Y849724D02*
Y877300D01*
G01X1288660Y948819D02*
Y845787D01*
G01Y948819D02*
Y845787D01*
G01X1296534Y948819D02*
G03X1284723Y960630I-11811J0D01*
G01X1288660Y948819D02*
G03X1284723Y952756I-3937J0D01*
G01X1288660Y948819D02*
G03X1284723Y952756I-3937J0D01*
G01X1331968Y958441D02*
G03X1317968Y972441I-14000J0D01*
G01X1331968Y-5685D02*
Y98622D01*
G01X1326061Y106496D02*
X1331967Y112402D01*
G01X1326061Y106496D02*
X1329998Y110433D01*
G01X1331967Y112402D02*
Y171732D01*
G01X1329998Y173701D02*
X1326061Y177638D01*
G01X1331967Y171732D02*
X1326061Y177638D01*
G01Y180394D02*
X1331967Y186299D01*
G01X1326061Y180394D02*
X1329998Y184331D01*
G01X1331967Y186299D02*
Y355630D01*
G01X1331968Y578937D02*
Y369409D01*
G01X1329998Y357598D02*
X1326061Y361535D01*
G01X1331967Y355630D02*
X1326061Y361535D01*
G01Y586811D02*
X1331967Y592717D01*
G01X1326061Y586811D02*
X1329998Y590748D01*
G01X1331967Y592717D02*
Y652047D01*
G01X1329998Y654016D02*
X1326061Y657953D01*
G01X1331967Y652047D02*
X1326061Y657953D01*
G01Y660709D02*
X1331967Y666614D01*
G01X1326061Y660709D02*
X1329998Y664646D01*
G01X1331967Y666614D02*
Y835945D01*
G01X1329998Y837913D02*
X1326061Y841850D01*
G01X1331967Y835945D02*
X1326061Y841850D01*
G01X1331968Y958441D02*
Y849724D01*
G54D15*
X35198Y333436D03*
Y337936D03*
X30108Y368932D03*
Y374132D03*
X66098Y369470D03*
X66147Y373979D03*
X66150Y378236D03*
X534333Y268971D03*
Y263971D03*
X530236Y322102D03*
X530136Y330602D03*
X530236Y326402D03*
X522800Y326000D03*
G54D24*
X41309Y391063D03*
G54D16*
X52705Y352395D03*
X48325Y352450D03*
X57398Y352460D03*
G54D25*
X69491Y365163D03*
X526200Y322000D03*
X533536Y334902D03*
X547700Y419000D03*
G54D17*
X43159Y377285D03*
X43072Y369247D03*
X51094Y390725D03*
X60052Y390692D03*
X55352Y390774D03*
X538000Y296700D03*
X548000Y432700D03*
G54D26*
X66091Y365163D03*
X522800Y322000D03*
X530136Y334902D03*
X544300Y419000D03*
G54D18*
X49902Y379652D03*
X52462D03*
X55022D03*
X57582D03*
Y363352D03*
X55022D03*
X52462D03*
X49902D03*
G54D27*
X67408Y391259D03*
G54D19*
X38128Y379932D03*
X45807Y393668D03*
X542500Y274771D03*
X634488Y77603D03*
G54D28*
X421500Y192300D03*
Y180700D03*
X435000Y192300D03*
Y180700D03*
X448500Y192300D03*
Y180700D03*
X462000Y192300D03*
Y180700D03*
G54D29*
X487625Y198086D03*
Y173286D03*
X512989Y198162D03*
Y173362D03*
X538135Y198177D03*
Y173377D03*
M02*
